FILE_TYPE = CONNECTIVITY;
{Allegro Design Entry HDL 17.2-2016 S081 (4005846) 1/11/2022}
"PAGE_NUMBER" = 119;
0"NC";
1"PVNN_TERM_CPU0\g";
2"PVNN_TERM_CPU0\g";
3"PVNN_TERM_CPU0\g";
4"PVNN_TERM_CPU0\g";
5"PVNN_TERM_CPU1\g";
6"PVNN_TERM_CPU1\g";
7"P3V3_AUX\g";
8"P3V3_AUX\g";
9"PVNN_TERM_CPU0\g";
10"PVNN_TERM_CPU0\g";
11"GND\g";
12"GND\g";
13"GND\g";
14"GND\g";
15"GND\g";
16"GND\g";
17"PD_CPU0_BIST_ENABLE";
18"PD_CPU1_BIST_ENABLE";
19"PD_CPU0_TXT_PLTEN";
20"PD_CPU1_TXT_PLTEN";
21"FM_CPU0_PKGID0";
22"FM_CPU0_PKGID1";
23"FM_CPU0_PKGID2";
24"FM_CPU1_PKGID2";
25"FM_CPU1_PKGID1";
26"FM_CPU1_PKGID0";
27"FM_CPU1_PROC_ID1";
28"FM_CPU1_PROC_ID0";
29"PU_TAP_ODT_CPU0_EN";
30"PU_TAP_ODT_CPU1_EN";
31"PU_CPU1_SOCKET_ID1";
32"PU_CPU1_SAFE_MODE_BOOT";
33"PU_CPU1_TXT_AGENT";
34"PU_CPU1_FRMAGENT";
35"PU_CPU0_SOCKET_ID1";
36"PU_CPU0_SOCKET_ID2";
37"PD_CPU0_DMIMODE_OVERRIDE";
38"PUD_XTAL_CPU0_MODE0";
39"PUD_XTAL_CPU0_MODE1";
40"PD_EXT_CLK_SEL_CPU0";
41"PUD_XTAL_CPU0_MODE0";
42"PU_CPU0_LEGACY_SKT";
43"PU_CPU0_SOCKET_ID0";
44"PU_CPU1_LEGACY_SKT";
45"PUD_XTAL_CPU1_MODE0";
46"PUD_XTAL_CPU1_MODE1";
47"PD_CPU0_ENH_MCECC_DIS";
48"PUD_XTAL_CPU0_MODE1";
49"H_CPU1_BMCINIT_LVC1";
50"PU_CPU1_SOCKET_ID0";
51"PU_CPU1_SOCKET_ID2";
52"PUD_XTAL_CPU1_MODE1";
53"H_CPU0_BMCINIT_LVC1";
54"PU_CPU0_FRMAGENT";
55"PU_CPU0_SAFE_MODE_BOOT";
56"PU_CPU0_TXT_AGENT";
57"FM_CPU0_PROC_ID0";
58"FM_CPU0_PROC_ID1";
59"PUD_XTAL_CPU1_MODE0";
60"PD_EXT_CLK_SEL_CPU1";
61"PD_CPU1_ENH_MCECC_DIS";
62"PD_CPU1_DMIMODE_OVERRIDE"CDS_PHYS_NET_NAME"PD_CPU0_DMICODE_OVERRIDE";
%"Q_RES"
"1","(-2100,475)","0","pure_quanta","I100";
;
PART_NUMBER"CS12402FB01"
VALUE"240"
TOLERANCE"1%"
MATERIAL"EMPTY"
$LOCATION"R262"
WATTAGE"1/16W"
PACK_TYPE"0402LF"
CDS_LIB"pure_quanta"
CDS_LOCATION"R262"
$SEC"1"
CDS_SEC"1";
"B"
$PN"2"32;
"A"
$PN"1"5;
%"Q_RES"
"1","(-2100,600)","0","pure_quanta","I101";
;
PART_NUMBER"CS12402FB01"
VALUE"240"
PACK_TYPE"0402LF"
WATTAGE"1/16W"
MATERIAL"EMPTY"
TOLERANCE"1%"
$LOCATION"R261"
CDS_LIB"pure_quanta"
CDS_LOCATION"R261"
$SEC"1"
CDS_SEC"1";
"B"
$PN"2"33;
"A"
$PN"1"5;
%"UNIVERSAL_POWER"
"1","(-2400,850)","0","logical_power","I102";
;
HDL_POWER"PVNN_TERM_CPU1"
CDS_LIB"logical_power";
"A"5;
%"Q_RES"
"1","(250,250)","0","pure_quanta","I116";
;
PART_NUMBER"CS12402FB01"
VALUE"240"
TOLERANCE"1%"
MATERIAL"EMPTY"
$LOCATION"R291"
CDS_LIB"pure_quanta"
PACK_TYPE"0402LF"
WATTAGE"1/16W"
CDS_LOCATION"R291"
$SEC"1"
CDS_SEC"1";
"B"
$PN"2"61;
"A"
$PN"1"15;
%"Q_RES"
"1","(-2100,350)","0","pure_quanta","I125";
;
PART_NUMBER"CS12402FB01"
VALUE"240"
MATERIAL"EMPTY"
TOLERANCE"1%"
$LOCATION"R263"
PACK_TYPE"0402LF"
WATTAGE"1/16W"
CDS_LIB"pure_quanta"
CDS_LOCATION"R263"
$SEC"1"
CDS_SEC"1";
"B"
$PN"2"34;
"A"
$PN"1"5;
%"Q_RES"
"1","(250,375)","0","pure_quanta","I135";
;
PART_NUMBER"CS12402FB01"
VALUE"240"
TOLERANCE"1%"
MATERIAL"CHIP"
$LOCATION"R290"
CDS_LIB"pure_quanta"
WATTAGE"1/16W"
PACK_TYPE"0402LF"
CDS_LOCATION"R290"
$SEC"1"
CDS_SEC"1";
"B"
$PN"2"62;
"A"
$PN"1"15;
%"Q_RES"
"1","(-2075,1925)","0","pure_quanta","I136";
;
PART_NUMBER"CS21002FB06"
WATTAGE"1/16W"
PACK_TYPE"0402LF"
MATERIAL"EMPTY"
TOLERANCE"1%"
VALUE"1K"
$LOCATION"R1009"
CDS_LIB"pure_quanta"
CDS_LOCATION"R1009"
$SEC"1"
CDS_SEC"1";
"B"
$PN"2"29;
"A"
$PN"1"9;
%"UNIVERSAL_POWER"
"1","(-2375,2150)","0","logical_power","I138";
;
HDL_POWER"PVNN_TERM_CPU0"
CDS_LIB"logical_power";
"A"9;
%"Q_RES"
"1","(-2100,-1225)","0","pure_quanta","I139";
;
PART_NUMBER"CS21002FB06"
MATERIAL"EMPTY"
TOLERANCE"1%"
WATTAGE"1/16W"
VALUE"1K"
PACK_TYPE"0402LF"
$LOCATION"R1008"
CDS_LIB"pure_quanta"
CDS_LOCATION"R1008"
$SEC"1"
CDS_SEC"1";
"B"
$PN"2"30;
"A"
$PN"1"6;
%"UNIVERSAL_POWER"
"1","(-2400,-1000)","0","logical_power","I141";
;
HDL_POWER"PVNN_TERM_CPU1"
CDS_LIB"logical_power";
"A"6;
%"Q_RES"
"1","(250,2250)","0","pure_quanta","I147";
;
PART_NUMBER"CS31002FB08"
WATTAGE"1/16W"
MATERIAL"CHIP"
VALUE"10K"
PACK_TYPE"0402LF"
TOLERANCE"1%"
$LOCATION"R283"
CDS_LIB"pure_quanta"
CDS_LOCATION"R283"
$SEC"1"
CDS_SEC"1";
"B"
$PN"2"21;
"A"
$PN"1"7;
%"Q_RES"
"1","(250,2125)","0","pure_quanta","I148";
;
PART_NUMBER"CS31002FB08"
MATERIAL"CHIP"
TOLERANCE"1%"
VALUE"10K"
$LOCATION"R284"
CDS_LIB"pure_quanta"
PACK_TYPE"0402LF"
WATTAGE"1/16W"
CDS_LOCATION"R284"
$SEC"1"
CDS_SEC"1";
"B"
$PN"2"22;
"A"
$PN"1"7;
%"UNIVERSAL_POWER"
"1","(-50,2375)","0","logical_power","I149";
;
HDL_POWER"P3V3_AUX"
CDS_LIB"logical_power";
"A"7;
%"Q_RES"
"1","(250,2000)","0","pure_quanta","I150";
;
PART_NUMBER"CS31002FB08"
VALUE"10K"
TOLERANCE"1%"
MATERIAL"CHIP"
$LOCATION"R285"
CDS_LIB"pure_quanta"
PACK_TYPE"0402LF"
WATTAGE"1/16W"
CDS_LOCATION"R285"
$SEC"1"
CDS_SEC"1";
"B"
$PN"2"23;
"A"
$PN"1"7;
%"Q_RES"
"1","(250,1875)","0","pure_quanta","I151";
;
PART_NUMBER"CS31002FB08"
TOLERANCE"1%"
VALUE"10K"
MATERIAL"CHIP"
$LOCATION"R286"
CDS_LIB"pure_quanta"
WATTAGE"1/16W"
PACK_TYPE"0402LF"
CDS_LOCATION"R286"
$SEC"1"
CDS_SEC"1";
"B"
$PN"2"57;
"A"
$PN"1"7;
%"Q_RES"
"1","(250,1750)","0","pure_quanta","I152";
;
PART_NUMBER"CS31002FB08"
MATERIAL"CHIP"
TOLERANCE"1%"
VALUE"10K"
$LOCATION"R287"
CDS_LIB"pure_quanta"
PACK_TYPE"0402LF"
WATTAGE"1/16W"
CDS_LOCATION"R287"
$SEC"1"
CDS_SEC"1";
"B"
$PN"2"58;
"A"
$PN"1"7;
%"Q_RES"
"1","(-2075,2450)","0","pure_quanta","I156";
;
PART_NUMBER"CS12402FB01"
VALUE"240"
MATERIAL"EMPTY"
TOLERANCE"1%"
$LOCATION"R1232"
CDS_LIB"pure_quanta"
WATTAGE"1/16W"
PACK_TYPE"0402LF"
CDS_LOCATION"R1232"
$SEC"1"
CDS_SEC"1";
"B"
$PN"2"38;
"A"
$PN"1"4;
%"Q_RES"
"1","(-2075,2325)","0","pure_quanta","I158";
;
PART_NUMBER"CS12402FB01"
MATERIAL"EMPTY"
TOLERANCE"1%"
VALUE"240"
$LOCATION"R1233"
CDS_LIB"pure_quanta"
WATTAGE"1/16W"
PACK_TYPE"0402LF"
CDS_LOCATION"R1233"
$SEC"1"
CDS_SEC"1";
"B"
$PN"2"39;
"A"
$PN"1"4;
%"Q_RES"
"1","(275,3100)","0","pure_quanta","I160";
;
PART_NUMBER"CS12402FB01"
VALUE"240"
MATERIAL"EMPTY"
TOLERANCE"1%"
$LOCATION"R1237"
CDS_LIB"pure_quanta"
WATTAGE"1/16W"
PACK_TYPE"0402LF"
CDS_LOCATION"R1237"
$SEC"1"
CDS_SEC"1";
"B"
$PN"2"40;
"A"
$PN"1"16;
%"Q_RES"
"1","(275,2975)","0","pure_quanta","I161";
;
PART_NUMBER"CS12402FB01"
MATERIAL"EMPTY"
VALUE"240"
TOLERANCE"1%"
$LOCATION"R1238"
PACK_TYPE"0402LF"
WATTAGE"1/16W"
CDS_LIB"pure_quanta"
CDS_LOCATION"R1238"
$SEC"1"
CDS_SEC"1";
"B"
$PN"2"41;
"A"
$PN"1"16;
%"Q_RES"
"1","(275,2850)","0","pure_quanta","I163";
;
PART_NUMBER"CS12402FB01"
MATERIAL"EMPTY"
VALUE"240"
TOLERANCE"1%"
$LOCATION"R1239"
PACK_TYPE"0402LF"
WATTAGE"1/16W"
CDS_LIB"pure_quanta"
CDS_LOCATION"R1239"
$SEC"1"
CDS_SEC"1";
"B"
$PN"2"48;
"A"
$PN"1"16;
%"Q_RES"
"1","(-2100,-650)","0","pure_quanta","I169";
;
PART_NUMBER"CS12402FB01"
TOLERANCE"1%"
MATERIAL"EMPTY"
VALUE"240"
$LOCATION"R1229"
PACK_TYPE"0402LF"
WATTAGE"1/16W"
CDS_LIB"pure_quanta"
CDS_LOCATION"R1229"
$SEC"1"
CDS_SEC"1";
"B"
$PN"2"45;
"A"
$PN"1"5;
%"Q_RES"
"1","(-2100,-775)","0","pure_quanta","I170";
;
PART_NUMBER"CS12402FB01"
TOLERANCE"1%"
MATERIAL"EMPTY"
VALUE"240"
$LOCATION"R1230"
PACK_TYPE"0402LF"
WATTAGE"1/16W"
CDS_LIB"pure_quanta"
CDS_LOCATION"R1230"
$SEC"1"
CDS_SEC"1";
"B"
$PN"2"46;
"A"
$PN"1"5;
%"UNIVERSAL_GND"
"1","(-75,-275)","0","logical_power","I171";
;
CDS_LIB"logical_power"
HDL_POWER"GND";
"A"15;
%"Q_RES"
"1","(250,125)","0","pure_quanta","I172";
;
PART_NUMBER"CS12402FB01"
MATERIAL"EMPTY"
TOLERANCE"1%"
VALUE"240"
$LOCATION"R3024"
CDS_LIB"pure_quanta"
WATTAGE"1/16W"
PACK_TYPE"0402LF"
CDS_LOCATION"R3024"
$SEC"1"
CDS_SEC"1";
"B"
$PN"2"60;
"A"
$PN"1"15;
%"Q_RES"
"1","(250,0)","0","pure_quanta","I176";
;
PART_NUMBER"CS12402FB01"
VALUE"240"
MATERIAL"EMPTY"
TOLERANCE"1%"
$LOCATION"R1235"
PACK_TYPE"0402LF"
WATTAGE"1/16W"
CDS_LIB"pure_quanta"
CDS_LOCATION"R1235"
$SEC"1"
CDS_SEC"1";
"B"
$PN"2"59;
"A"
$PN"1"15;
%"Q_RES"
"1","(250,-125)","0","pure_quanta","I177";
;
PART_NUMBER"CS12402FB01"
TOLERANCE"1%"
VALUE"240"
MATERIAL"EMPTY"
$LOCATION"R1236"
PACK_TYPE"0402LF"
WATTAGE"1/16W"
CDS_LIB"pure_quanta"
CDS_LOCATION"R1236"
$SEC"1"
CDS_SEC"1";
"B"
$PN"2"52;
"A"
$PN"1"15;
%"UNIVERSAL_POWER"
"1","(-2375,3825)","0","logical_power","I18";
;
HDL_POWER"PVNN_TERM_CPU0"
CDS_LIB"logical_power";
"A"4;
%"Q_RES"
"1","(2975,3375)","5","pure_quanta","I196";
;
PART_NUMBER"CS12402FB01"
PACK_TYPE"0402LF"
WATTAGE"1/16W"
VALUE"240"
TOLERANCE"1%"
MATERIAL"EMPTY"
$LOCATION"R292"
CDS_LIB"pure_quanta"
CDS_LOCATION"R292"
$SEC"1"
CDS_SEC"1";
"B"
$PN"2"19;
"A"
$PN"1"2;
%"UNIVERSAL_GND"
"1","(2975,2800)","0","logical_power","I197";
;
CDS_LIB"logical_power"
HDL_POWER"GND";
"A"13;
%"UNIVERSAL_POWER"
"1","(2975,3675)","0","logical_power","I210";
;
HDL_POWER"PVNN_TERM_CPU0"
CDS_LIB"logical_power";
"A"2;
%"Q_RES"
"1","(2975,3050)","5","pure_quanta","I211";
;
PART_NUMBER"CS12402FB01"
TOLERANCE"1%"
VALUE"240"
PACK_TYPE"0402LF"
WATTAGE"1/16W"
MATERIAL"EMPTY"
LOCATION"R293"
CDS_LIB"pure_quanta"
$SEC"1"
CDS_SEC"1";
"B"
$PN"2"13;
"A"
$PN"1"19;
%"UNIVERSAL_GND"
"1","(5075,2775)","0","logical_power","I213";
;
CDS_LIB"logical_power"
HDL_POWER"GND";
"A"14;
%"UNIVERSAL_POWER"
"1","(5075,3650)","0","logical_power","I214";
;
HDL_POWER"PVNN_TERM_CPU0"
CDS_LIB"logical_power";
"A"3;
%"Q_RES"
"1","(5075,3350)","5","pure_quanta","I215";
;
PART_NUMBER"CS12402FB01"
TOLERANCE"1%"
VALUE"240"
PACK_TYPE"0402LF"
WATTAGE"1/16W"
MATERIAL"EMPTY"
$LOCATION"R4262"
CDS_LIB"pure_quanta"
CDS_LOCATION"R4262"
$SEC"1"
CDS_SEC"1";
"B"
$PN"2"17;
"A"
$PN"1"3;
%"Q_RES"
"1","(5075,3025)","5","pure_quanta","I216";
;
PART_NUMBER"CS12402FB01"
VALUE"240"
TOLERANCE"1%"
WATTAGE"1/16W"
PACK_TYPE"0402LF"
MATERIAL"EMPTY"
$LOCATION"R4263"
CDS_LIB"pure_quanta"
CDS_LOCATION"R4263"
$SEC"1"
CDS_SEC"1";
"B"
$PN"2"14;
"A"
$PN"1"17;
%"UNIVERSAL_POWER"
"1","(5050,-650)","0","logical_power","I218";
;
HDL_POWER"PVNN_TERM_CPU0"
CDS_LIB"logical_power";
"A"10;
%"Q_RES"
"1","(5050,-950)","5","pure_quanta","I219";
;
PART_NUMBER"CS12402FB01"
PACK_TYPE"0402LF"
WATTAGE"1/16W"
TOLERANCE"1%"
VALUE"240"
MATERIAL"EMPTY"
$LOCATION"R4260"
CDS_LIB"pure_quanta"
CDS_LOCATION"R4260"
$SEC"1"
CDS_SEC"1";
"B"
$PN"2"18;
"A"
$PN"1"10;
%"Q_RES"
"1","(5050,-1275)","5","pure_quanta","I220";
;
PART_NUMBER"CS12402FB01"
PACK_TYPE"0402LF"
MATERIAL"EMPTY"
TOLERANCE"1%"
VALUE"240"
WATTAGE"1/16W"
$LOCATION"R4261"
CDS_LIB"pure_quanta"
CDS_LOCATION"R4261"
$SEC"1"
CDS_SEC"1";
"B"
$PN"2"11;
"A"
$PN"1"18;
%"UNIVERSAL_GND"
"1","(5050,-1525)","0","logical_power","I221";
;
CDS_LIB"logical_power"
HDL_POWER"GND";
"A"11;
%"UNIVERSAL_POWER"
"1","(2950,-625)","0","logical_power","I223";
;
HDL_POWER"PVNN_TERM_CPU0"
CDS_LIB"logical_power";
"A"1;
%"Q_RES"
"1","(2950,-925)","5","pure_quanta","I224";
;
PART_NUMBER"CS12402FB01"
PACK_TYPE"0402LF"
TOLERANCE"1%"
MATERIAL"EMPTY"
WATTAGE"1/16W"
VALUE"240"
LOCATION"R288"
CDS_LIB"pure_quanta"
$SEC"1"
CDS_SEC"1";
"B"
$PN"2"20;
"A"
$PN"1"1;
%"Q_RES"
"1","(2950,-1250)","5","pure_quanta","I225";
;
PART_NUMBER"CS12402FB01"
PACK_TYPE"0402LF"
WATTAGE"1/16W"
VALUE"240"
TOLERANCE"1%"
MATERIAL"EMPTY"
LOCATION"R289"
CDS_LIB"pure_quanta"
$SEC"1"
CDS_SEC"1";
"B"
$PN"2"12;
"A"
$PN"1"20;
%"UNIVERSAL_GND"
"1","(2950,-1500)","0","logical_power","I226";
;
CDS_LIB"logical_power"
HDL_POWER"GND";
"A"12;
%"UNIVERSAL_GND"
"1","(-50,2700)","0","logical_power","I44";
;
CDS_LIB"logical_power"
HDL_POWER"GND";
"A"16;
%"Q_RES"
"1","(-2075,2700)","0","pure_quanta","I53";
;
PART_NUMBER"CS12402FB01"
TOLERANCE"1%"
MATERIAL"CHIP"
VALUE"240"
$LOCATION"R282"
CDS_LIB"pure_quanta"
PACK_TYPE"0402LF"
WATTAGE"1/16W"
CDS_LOCATION"R282"
$SEC"1"
CDS_SEC"1";
"B"
$PN"2"42;
"A"
$PN"1"4;
%"Q_RES"
"1","(-2075,3075)","0","pure_quanta","I54";
;
PART_NUMBER"CS12402FB01"
MATERIAL"EMPTY"
VALUE"240"
TOLERANCE"1%"
$LOCATION"R279"
CDS_LIB"pure_quanta"
PACK_TYPE"0402LF"
WATTAGE"1/16W"
CDS_LOCATION"R279"
$SEC"1"
CDS_SEC"1";
"B"
$PN"2"43;
"A"
$PN"1"4;
%"Q_RES"
"1","(-2075,2950)","0","pure_quanta","I57";
;
PART_NUMBER"CS12402FB01"
TOLERANCE"1%"
MATERIAL"EMPTY"
VALUE"240"
$LOCATION"R280"
CDS_LIB"pure_quanta"
WATTAGE"1/16W"
PACK_TYPE"0402LF"
CDS_LOCATION"R280"
$SEC"1"
CDS_SEC"1";
"B"
$PN"2"35;
"A"
$PN"1"4;
%"Q_RES"
"1","(-2075,2825)","0","pure_quanta","I58";
;
PART_NUMBER"CS12402FB01"
MATERIAL"EMPTY"
TOLERANCE"1%"
VALUE"240"
$LOCATION"R281"
CDS_LIB"pure_quanta"
PACK_TYPE"0402LF"
WATTAGE"1/16W"
CDS_LOCATION"R281"
$SEC"1"
CDS_SEC"1";
"B"
$PN"2"36;
"A"
$PN"1"4;
%"Q_RES"
"1","(-2075,3200)","0","pure_quanta","I61";
;
PART_NUMBER"CS12402FB01"
MATERIAL"EMPTY"
VALUE"240"
TOLERANCE"1%"
$LOCATION"R278"
WATTAGE"1/16W"
PACK_TYPE"0402LF"
CDS_LIB"pure_quanta"
CDS_LOCATION"R278"
$SEC"1"
CDS_SEC"1";
"B"
$PN"2"53;
"A"
$PN"1"4;
%"Q_RES"
"1","(-2075,3325)","0","pure_quanta","I62";
;
PART_NUMBER"CS12402FB01"
MATERIAL"CHIP"
TOLERANCE"1%"
VALUE"240"
$LOCATION"R277"
CDS_LIB"pure_quanta"
PACK_TYPE"0402LF"
WATTAGE"1/16W"
CDS_LOCATION"R277"
$SEC"1"
CDS_SEC"1";
"B"
$PN"2"54;
"A"
$PN"1"4;
%"Q_RES"
"1","(-2075,3450)","0","pure_quanta","I66";
;
PART_NUMBER"CS12402FB01"
TOLERANCE"1%"
VALUE"240"
MATERIAL"EMPTY"
$LOCATION"R276"
CDS_LIB"pure_quanta"
PACK_TYPE"0402LF"
WATTAGE"1/16W"
CDS_LOCATION"R276"
$SEC"1"
CDS_SEC"1";
"B"
$PN"2"55;
"A"
$PN"1"4;
%"Q_RES"
"1","(-2075,3575)","0","pure_quanta","I68";
;
PART_NUMBER"CS12402FB01"
WATTAGE"1/16W"
TOLERANCE"1%"
MATERIAL"CHIP"
VALUE"240"
PACK_TYPE"0402LF"
$LOCATION"R275"
CDS_LIB"pure_quanta"
CDS_LOCATION"R275"
$SEC"1"
CDS_SEC"1";
"B"
$PN"2"56;
"A"
$PN"1"4;
%"Q_RES"
"1","(275,3350)","0","pure_quanta","I71";
;
PART_NUMBER"CS12402FB01"
MATERIAL"EMPTY"
TOLERANCE"1%"
VALUE"240"
$LOCATION"R294"
CDS_LIB"pure_quanta"
PACK_TYPE"0402LF"
WATTAGE"1/16W"
CDS_LOCATION"R294"
$SEC"1"
CDS_SEC"1";
"B"
$PN"2"37;
"A"
$PN"1"16;
%"Q_RES"
"1","(275,3225)","0","pure_quanta","I72";
;
PART_NUMBER"CS12402FB01"
VALUE"240"
TOLERANCE"1%"
MATERIAL"EMPTY"
$LOCATION"R295"
CDS_LIB"pure_quanta"
WATTAGE"1/16W"
PACK_TYPE"0402LF"
CDS_LOCATION"R295"
$SEC"1"
CDS_SEC"1";
"B"
$PN"2"47;
"A"
$PN"1"16;
%"Q_RES"
"1","(225,-1275)","0","pure_quanta","I88";
;
PART_NUMBER"CS31002FB08"
MATERIAL"CHIP"
TOLERANCE"1%"
VALUE"10K"
$LOCATION"R274"
CDS_LIB"pure_quanta"
PACK_TYPE"0402LF"
WATTAGE"1/16W"
CDS_LOCATION"R274"
$SEC"1"
CDS_SEC"1";
"B"
$PN"2"27;
"A"
$PN"1"8;
%"Q_RES"
"1","(225,-1150)","0","pure_quanta","I89";
;
PART_NUMBER"CS31002FB08"
MATERIAL"CHIP"
TOLERANCE"1%"
VALUE"10K"
$LOCATION"R273"
CDS_LIB"pure_quanta"
WATTAGE"1/16W"
PACK_TYPE"0402LF"
CDS_LOCATION"R273"
$SEC"1"
CDS_SEC"1";
"B"
$PN"2"28;
"A"
$PN"1"8;
%"Q_RES"
"1","(225,-1025)","0","pure_quanta","I90";
;
PART_NUMBER"CS31002FB08"
VALUE"10K"
TOLERANCE"1%"
MATERIAL"CHIP"
$LOCATION"R272"
CDS_LIB"pure_quanta"
WATTAGE"1/16W"
PACK_TYPE"0402LF"
CDS_LOCATION"R272"
$SEC"1"
CDS_SEC"1";
"B"
$PN"2"24;
"A"
$PN"1"8;
%"UNIVERSAL_POWER"
"1","(-75,-625)","0","logical_power","I91";
;
HDL_POWER"P3V3_AUX"
CDS_LIB"logical_power";
"A"8;
%"Q_RES"
"1","(225,-900)","0","pure_quanta","I92";
;
PART_NUMBER"CS31002FB08"
MATERIAL"CHIP"
TOLERANCE"1%"
VALUE"10K"
$LOCATION"R271"
CDS_LIB"pure_quanta"
PACK_TYPE"0402LF"
WATTAGE"1/16W"
CDS_LOCATION"R271"
$SEC"1"
CDS_SEC"1";
"B"
$PN"2"25;
"A"
$PN"1"8;
%"Q_RES"
"1","(225,-775)","0","pure_quanta","I93";
;
PART_NUMBER"CS31002FB08"
MATERIAL"CHIP"
PACK_TYPE"0402LF"
TOLERANCE"1%"
WATTAGE"1/16W"
VALUE"10K"
$LOCATION"R270"
CDS_LIB"pure_quanta"
CDS_LOCATION"R270"
$SEC"1"
CDS_SEC"1";
"B"
$PN"2"26;
"A"
$PN"1"8;
%"Q_RES"
"1","(-2100,-275)","0","pure_quanta","I94";
;
PART_NUMBER"CS12402FB01"
MATERIAL"EMPTY"
VALUE"240"
TOLERANCE"1%"
$LOCATION"R268"
CDS_LIB"pure_quanta"
PACK_TYPE"0402LF"
WATTAGE"1/16W"
CDS_LOCATION"R268"
$SEC"1"
CDS_SEC"1";
"B"
$PN"2"44;
"A"
$PN"1"5;
%"Q_RES"
"1","(-2100,-150)","0","pure_quanta","I95";
;
PART_NUMBER"CS12402FB01"
VALUE"240"
TOLERANCE"1%"
MATERIAL"EMPTY"
$LOCATION"R267"
WATTAGE"1/16W"
PACK_TYPE"0402LF"
CDS_LIB"pure_quanta"
CDS_LOCATION"R267"
$SEC"1"
CDS_SEC"1";
"B"
$PN"2"51;
"A"
$PN"1"5;
%"Q_RES"
"1","(-2100,-25)","0","pure_quanta","I96";
;
PART_NUMBER"CS12402FB01"
VALUE"240"
MATERIAL"EMPTY"
TOLERANCE"1%"
$LOCATION"R266"
PACK_TYPE"0402LF"
WATTAGE"1/16W"
CDS_LIB"pure_quanta"
CDS_LOCATION"R266"
$SEC"1"
CDS_SEC"1";
"B"
$PN"2"31;
"A"
$PN"1"5;
%"Q_RES"
"1","(-2100,100)","0","pure_quanta","I97";
;
PART_NUMBER"CS12402FB01"
MATERIAL"CHIP"
VALUE"240"
TOLERANCE"1%"
$LOCATION"R265"
CDS_LIB"pure_quanta"
PACK_TYPE"0402LF"
WATTAGE"1/16W"
CDS_LOCATION"R265"
$SEC"1"
CDS_SEC"1";
"B"
$PN"2"50;
"A"
$PN"1"5;
%"Q_RES"
"1","(-2100,225)","0","pure_quanta","I98";
;
PART_NUMBER"CS12402FB01"
TOLERANCE"1%"
MATERIAL"EMPTY"
VALUE"240"
$LOCATION"R264"
CDS_LIB"pure_quanta"
PACK_TYPE"0402LF"
WATTAGE"1/16W"
CDS_LOCATION"R264"
$SEC"1"
CDS_SEC"1";
"B"
$PN"2"49;
"A"
$PN"1"5;
END.
